(kicad_pcb
	(version 20241229)
	(generator "pcbnew")
	(generator_version "9.0")
	(general
		(thickness 1.6642)
		(legacy_teardrops no)
	)
	(paper "A3")
	(title_block
		(title "PolarFire SoM")
		(date "2025-07-22")
		(rev "1.1.4")
		(company "Antmicro Ltd")
		(comment 1 "www.antmicro.com")
		(comment 9 "footprints 137-140 of 470")
	)
	(layers
		(0 "F.Cu" mixed)
		(4 "In1.Cu" power)
		(6 "In2.Cu" signal)
		(8 "In3.Cu" power)
		(10 "In4.Cu" signal)
		(12 "In5.Cu" power)
		(14 "In6.Cu" power)
		(16 "In7.Cu" signal)
		(18 "In8.Cu" power)
		(20 "In9.Cu" signal)
		(22 "In10.Cu" power)
		(24 "In11.Cu" signal)
		(26 "In12.Cu" signal)
		(2 "B.Cu" mixed)
		(9 "F.Adhes" user "F.Adhesive")
		(11 "B.Adhes" user "B.Adhesive")
		(13 "F.Paste" user)
		(15 "B.Paste" user)
		(5 "F.SilkS" user "F.Silkscreen")
		(7 "B.SilkS" user "B.Silkscreen")
		(1 "F.Mask" user)
		(3 "B.Mask" user)
		(17 "Dwgs.User" user "User.Drawings")
		(19 "Cmts.User" user "User.Comments")
		(21 "Eco1.User" user "User.Eco1")
		(23 "Eco2.User" user "User.Eco2")
		(25 "Edge.Cuts" user)
		(27 "Margin" user)
		(31 "F.CrtYd" user "F.Courtyard")
		(29 "B.CrtYd" user "B.Courtyard")
		(35 "F.Fab" user)
		(33 "B.Fab" user)
	)
	(footprint "antmicro-footprints:C_0402_1005Metric"
		(layer "B.Cu")
		(at 175.29 122.9395 -90)
		(descr "Capacitor SMD 0402")
		(tags "capacitor SMD 0402")
		(property "Reference" "C150"
			(at -1.2395 -1.32 90)
			(unlocked yes)
			(layer "B.SilkS")
			(effects
				(font
					(size 0.7 0.7)
					(thickness 0.15)
				)
				(justify left bottom mirror)
			)
		)
		(property "Value" "C_1u_0402"
			(at -1.022927 -2.155213 90)
			(layer "B.Fab")
			(hide yes)
			(effects
				(font
					(size 0.7 0.7)
					(thickness 0.15)
				)
				(justify left bottom mirror)
			)
		)
		(property "Datasheet" "https://product.tdk.com/en/search/capacitor/ceramic/mlcc/info?part_no=C1005X6S1A105K050BC"
			(at 0 0 270)
			(layer "F.Fab")
			(hide yes)
			(effects
				(font
					(size 1.27 1.27)
					(thickness 0.15)
				)
			)
		)
		(property "Description" "SMD Multilayer Ceramic Capacitor, 1 µF, 10 V, 0402 [1005 Metric], ± 10%, X6S, C"
			(at 0 0 270)
			(layer "F.Fab")
			(hide yes)
			(effects
				(font
					(size 1.27 1.27)
					(thickness 0.15)
				)
			)
		)
		(property "Author" "Antmicro"
			(at 52.3505 298.2295 0)
			(layer "B.Fab")
			(hide yes)
			(effects
				(font
					(size 1 1)
					(thickness 0.15)
				)
				(justify mirror)
			)
		)
		(property "Dielectric" "X5R"
			(at 52.3505 298.2295 0)
			(layer "B.Fab")
			(hide yes)
			(effects
				(font
					(size 1 1)
					(thickness 0.15)
				)
				(justify mirror)
			)
		)
		(property "License" "Apache-2.0"
			(at 52.3505 298.2295 0)
			(layer "B.Fab")
			(hide yes)
			(effects
				(font
					(size 1 1)
					(thickness 0.15)
				)
				(justify mirror)
			)
		)
		(property "MPN" "C1005X6S1A105K050BC"
			(at 52.3505 298.2295 0)
			(layer "B.Fab")
			(hide yes)
			(effects
				(font
					(size 1 1)
					(thickness 0.15)
				)
				(justify mirror)
			)
		)
		(property "Manufacturer" "TDK"
			(at 52.3505 298.2295 0)
			(layer "B.Fab")
			(hide yes)
			(effects
				(font
					(size 1 1)
					(thickness 0.15)
				)
				(justify mirror)
			)
		)
		(property "Public" ""
			(at 52.3505 298.2295 0)
			(layer "B.Fab")
			(hide yes)
			(effects
				(font
					(size 1 1)
					(thickness 0.15)
				)
				(justify mirror)
			)
		)
		(property "Val" "1u"
			(at 52.3505 298.2295 0)
			(layer "B.Fab")
			(hide yes)
			(effects
				(font
					(size 1 1)
					(thickness 0.15)
				)
				(justify mirror)
			)
		)
		(property "Voltage" "16V"
			(at 52.3505 298.2295 0)
			(layer "B.Fab")
			(hide yes)
			(effects
				(font
					(size 1 1)
					(thickness 0.15)
				)
				(justify mirror)
			)
		)
		(sheetname "/LPDDR4/")
		(sheetfile "lpddr.kicad_sch")
		(attr smd)
		(fp_rect
			(start -0.925 0.47)
			(end 0.925 -0.47)
			(stroke
				(width 0.05)
				(type default)
			)
			(fill no)
			(layer "B.CrtYd")
		)
		(fp_line
			(start -0.494 0.25)
			(end 0.504 0.25)
			(stroke
				(width 0.15)
				(type solid)
			)
			(layer "B.Fab")
		)
		(fp_line
			(start 0.504 0.25)
			(end 0.504 -0.248)
			(stroke
				(width 0.15)
				(type solid)
			)
			(layer "B.Fab")
		)
		(fp_line
			(start -0.494 -0.248)
			(end -0.494 0.25)
			(stroke
				(width 0.15)
				(type solid)
			)
			(layer "B.Fab")
		)
		(fp_line
			(start 0.504 -0.248)
			(end -0.494 -0.248)
			(stroke
				(width 0.15)
				(type solid)
			)
			(layer "B.Fab")
		)
		(fp_text user "${REFERENCE}"
			(at -0.939 -4.599 90)
			(layer "B.Fab")
			(effects
				(font
					(size 0.7 0.7)
					(thickness 0.15)
				)
				(justify left bottom mirror)
			)
		)
		(fp_text user "License: Apache-2.0"
			(at -0.939 -5.799 90)
			(layer "B.Fab")
			(effects
				(font
					(size 0.7 0.7)
					(thickness 0.15)
				)
				(justify left bottom mirror)
			)
		)
		(fp_text user "Author: Antmicro"
			(at -0.939 -3.399 90)
			(layer "B.Fab")
			(effects
				(font
					(size 0.7 0.7)
					(thickness 0.15)
				)
				(justify left bottom mirror)
			)
		)
		(pad "1" smd roundrect
			(at -0.48 0 270)
			(size 0.59 0.64)
			(layers "B.Cu" "B.Mask" "B.Paste")
			(roundrect_rratio 0.25)
			(net 417 "GND")
			(pintype "passive")
		)
		(pad "2" smd roundrect
			(at 0.48 0 270)
			(size 0.59 0.64)
			(layers "B.Cu" "B.Mask" "B.Paste")
			(roundrect_rratio 0.25)
			(net 2 "+1V1")
			(pintype "passive")
		)
	)
	(footprint "antmicro-footprints:R_0402_1005Metric"
		(layer "B.Cu")
		(at 192 123.25)
		(descr "Resistor SMD 0402")
		(tags "resistor SMD 0402")
		(property "Reference" "R74"
			(at 0.875 -0.525 180)
			(layer "B.SilkS")
			(effects
				(font
					(size 0.7 0.7)
					(thickness 0.15)
				)
				(justify left bottom mirror)
			)
		)
		(property "Value" "R_1k_0402"
			(at -1.011843 -1.772047 180)
			(layer "B.Fab")
			(hide yes)
			(effects
				(font
					(size 0.7 0.7)
					(thickness 0.15)
				)
				(justify left bottom mirror)
			)
		)
		(property "Datasheet" "https://www.bourns.com/docs/product-datasheets/cr.pdf"
			(at 0 0 0)
			(layer "F.Fab")
			(hide yes)
			(effects
				(font
					(size 1.27 1.27)
					(thickness 0.15)
				)
			)
		)
		(property "Description" "SMD Chip Resistor, 1 kohm, ± 1%, 63 mW, 0402 [1005 Metric], Thick Film, General Purpose"
			(at 0 0 0)
			(layer "F.Fab")
			(hide yes)
			(effects
				(font
					(size 1.27 1.27)
					(thickness 0.15)
				)
			)
		)
		(property "Author" "Antmicro"
			(at 0 0 0)
			(layer "B.Fab")
			(hide yes)
			(effects
				(font
					(size 1 1)
					(thickness 0.15)
				)
				(justify mirror)
			)
		)
		(property "License" "Apache-2.0"
			(at 0 0 0)
			(layer "B.Fab")
			(hide yes)
			(effects
				(font
					(size 1 1)
					(thickness 0.15)
				)
				(justify mirror)
			)
		)
		(property "MPN" "CR0402-FX-1001GLF"
			(at 0 0 0)
			(layer "B.Fab")
			(hide yes)
			(effects
				(font
					(size 1 1)
					(thickness 0.15)
				)
				(justify mirror)
			)
		)
		(property "Manufacturer" "Bourns"
			(at 0 0 0)
			(layer "B.Fab")
			(hide yes)
			(effects
				(font
					(size 1 1)
					(thickness 0.15)
				)
				(justify mirror)
			)
		)
		(property "Public" ""
			(at 0 0 0)
			(layer "B.Fab")
			(hide yes)
			(effects
				(font
					(size 1 1)
					(thickness 0.15)
				)
				(justify mirror)
			)
		)
		(property "Tolerance" "1%"
			(at 0 0 0)
			(layer "B.Fab")
			(hide yes)
			(effects
				(font
					(size 1 1)
					(thickness 0.15)
				)
				(justify mirror)
			)
		)
		(property "Val" "1k"
			(at 0 0 0)
			(layer "B.Fab")
			(hide yes)
			(effects
				(font
					(size 1 1)
					(thickness 0.15)
				)
				(justify mirror)
			)
		)
		(sheetname "/FPGA MSS/")
		(sheetfile "fpga-mss.kicad_sch")
		(attr smd)
		(fp_rect
			(start -0.925 0.47)
			(end 0.925 -0.47)
			(stroke
				(width 0.05)
				(type default)
			)
			(fill no)
			(layer "B.CrtYd")
		)
		(fp_rect
			(start -0.5 0.25)
			(end 0.5 -0.25)
			(stroke
				(width 0.15)
				(type solid)
			)
			(fill no)
			(layer "B.Fab")
		)
		(fp_text user "Author: Antmicro"
			(at -0.95 -4.169 180)
			(layer "B.Fab")
			(effects
				(font
					(size 0.7 0.7)
					(thickness 0.15)
				)
				(justify left bottom mirror)
			)
		)
		(fp_text user "License: Apache-2.0"
			(at -0.95 -5.169 180)
			(layer "B.Fab")
			(effects
				(font
					(size 0.7 0.7)
					(thickness 0.15)
				)
				(justify left bottom mirror)
			)
		)
		(fp_text user "${REFERENCE}"
			(at -0.95 -3.168 180)
			(layer "B.Fab")
			(effects
				(font
					(size 0.7 0.7)
					(thickness 0.15)
				)
				(justify left bottom mirror)
			)
		)
		(pad "1" smd roundrect
			(at -0.48 0)
			(size 0.59 0.64)
			(layers "B.Cu" "B.Mask" "B.Paste")
			(roundrect_rratio 0.25)
			(net 2 "+1V1")
			(pintype "passive")
		)
		(pad "2" smd roundrect
			(at 0.48 0)
			(size 0.59 0.64)
			(layers "B.Cu" "B.Mask" "B.Paste")
			(roundrect_rratio 0.25)
			(net 270 "Net-(U1G-MSS_DDR_VREF_IN)")
			(pintype "passive")
		)
	)
	(footprint "antmicro-footprints:C_0402_1005Metric"
		(layer "B.Cu")
		(at 197.99 132.79 90)
		(descr "Capacitor SMD 0402")
		(tags "capacitor SMD 0402")
		(property "Reference" "C40"
			(at 7.19 -9.615 270)
			(layer "B.SilkS")
			(effects
				(font
					(size 0.7 0.7)
					(thickness 0.15)
				)
				(justify left bottom mirror)
			)
		)
		(property "Value" "C_10n_0402"
			(at -1.022927 -2.155213 270)
			(layer "B.Fab")
			(hide yes)
			(effects
				(font
					(size 0.7 0.7)
					(thickness 0.15)
				)
				(justify left bottom mirror)
			)
		)
		(property "Datasheet" "https://www.murata.com/products/productdetail?partno=GRM155R71H103KA88%23"
			(at 0 0 90)
			(layer "F.Fab")
			(hide yes)
			(effects
				(font
					(size 1.27 1.27)
					(thickness 0.15)
				)
			)
		)
		(property "Description" "SMD Multilayer Ceramic Capacitor, 10000 pF, 50 V, 0402 [1005 Metric], ± 10%, X7R, GRM Series"
			(at 0 0 90)
			(layer "F.Fab")
			(hide yes)
			(effects
				(font
					(size 1.27 1.27)
					(thickness 0.15)
				)
			)
		)
		(property "Author" "Antmicro"
			(at 330.78 -65.2 0)
			(layer "B.Fab")
			(hide yes)
			(effects
				(font
					(size 1 1)
					(thickness 0.15)
				)
				(justify mirror)
			)
		)
		(property "Dielectric" "X7R"
			(at 330.78 -65.2 0)
			(layer "B.Fab")
			(hide yes)
			(effects
				(font
					(size 1 1)
					(thickness 0.15)
				)
				(justify mirror)
			)
		)
		(property "License" "Apache-2.0"
			(at 330.78 -65.2 0)
			(layer "B.Fab")
			(hide yes)
			(effects
				(font
					(size 1 1)
					(thickness 0.15)
				)
				(justify mirror)
			)
		)
		(property "MPN" "GRM155R71H103KA88D"
			(at 330.78 -65.2 0)
			(layer "B.Fab")
			(hide yes)
			(effects
				(font
					(size 1 1)
					(thickness 0.15)
				)
				(justify mirror)
			)
		)
		(property "Manufacturer" "Murata"
			(at 330.78 -65.2 0)
			(layer "B.Fab")
			(hide yes)
			(effects
				(font
					(size 1 1)
					(thickness 0.15)
				)
				(justify mirror)
			)
		)
		(property "Public" ""
			(at 330.78 -65.2 0)
			(layer "B.Fab")
			(hide yes)
			(effects
				(font
					(size 1 1)
					(thickness 0.15)
				)
				(justify mirror)
			)
		)
		(property "Val" "10n"
			(at 330.78 -65.2 0)
			(layer "B.Fab")
			(hide yes)
			(effects
				(font
					(size 1 1)
					(thickness 0.15)
				)
				(justify mirror)
			)
		)
		(property "Voltage" "50V"
			(at 330.78 -65.2 0)
			(layer "B.Fab")
			(hide yes)
			(effects
				(font
					(size 1 1)
					(thickness 0.15)
				)
				(justify mirror)
			)
		)
		(sheetname "/FPGA Supply/")
		(sheetfile "fpga-supply.kicad_sch")
		(attr smd)
		(fp_rect
			(start -0.925 0.47)
			(end 0.925 -0.47)
			(stroke
				(width 0.05)
				(type default)
			)
			(fill no)
			(layer "B.CrtYd")
		)
		(fp_line
			(start 0.504 -0.248)
			(end -0.494 -0.248)
			(stroke
				(width 0.15)
				(type solid)
			)
			(layer "B.Fab")
		)
		(fp_line
			(start -0.494 -0.248)
			(end -0.494 0.25)
			(stroke
				(width 0.15)
				(type solid)
			)
			(layer "B.Fab")
		)
		(fp_line
			(start 0.504 0.25)
			(end 0.504 -0.248)
			(stroke
				(width 0.15)
				(type solid)
			)
			(layer "B.Fab")
		)
		(fp_line
			(start -0.494 0.25)
			(end 0.504 0.25)
			(stroke
				(width 0.15)
				(type solid)
			)
			(layer "B.Fab")
		)
		(fp_text user "License: Apache-2.0"
			(at -0.939 -5.799 270)
			(layer "B.Fab")
			(effects
				(font
					(size 0.7 0.7)
					(thickness 0.15)
				)
				(justify left bottom mirror)
			)
		)
		(fp_text user "Author: Antmicro"
			(at -0.939 -3.399 270)
			(layer "B.Fab")
			(effects
				(font
					(size 0.7 0.7)
					(thickness 0.15)
				)
				(justify left bottom mirror)
			)
		)
		(fp_text user "${REFERENCE}"
			(at -0.939 -4.599 270)
			(layer "B.Fab")
			(effects
				(font
					(size 0.7 0.7)
					(thickness 0.15)
				)
				(justify left bottom mirror)
			)
		)
		(pad "1" smd roundrect
			(at -0.48 0 90)
			(size 0.59 0.64)
			(layers "B.Cu" "B.Mask" "B.Paste")
			(roundrect_rratio 0.25)
			(net 417 "GND")
			(pintype "passive")
		)
		(pad "2" smd roundrect
			(at 0.48 0 90)
			(size 0.59 0.64)
			(layers "B.Cu" "B.Mask" "B.Paste")
			(roundrect_rratio 0.25)
			(net 47 "+1V05")
			(pintype "passive")
		)
	)
	(footprint "antmicro-footprints:R_0402_1005Metric"
		(layer "B.Cu")
		(at 224.1 138.61 -90)
		(descr "Resistor SMD 0402")
		(tags "resistor SMD 0402")
		(property "Reference" "R52"
			(at -3.14 -0.39 90)
			(layer "B.SilkS")
			(effects
				(font
					(size 0.7 0.7)
					(thickness 0.15)
				)
				(justify left bottom mirror)
			)
		)
		(property "Value" "R_10k_0402"
			(at -1.011843 -1.772047 90)
			(layer "B.Fab")
			(hide yes)
			(effects
				(font
					(size 0.7 0.7)
					(thickness 0.15)
				)
				(justify left bottom mirror)
			)
		)
		(property "Datasheet" "https://www.bourns.com/docs/product-datasheets/cr.pdf"
			(at 0 0 270)
			(layer "F.Fab")
			(hide yes)
			(effects
				(font
					(size 1.27 1.27)
					(thickness 0.15)
				)
			)
		)
		(property "Description" "SMD Chip Resistor, 10 kohm, ± 1%, 62.5 mW, 0402 [1005 Metric], Thick Film, General Purpose"
			(at 0 0 270)
			(layer "F.Fab")
			(hide yes)
			(effects
				(font
					(size 1.27 1.27)
					(thickness 0.15)
				)
			)
		)
		(property "Author" "Antmicro"
			(at 85.49 362.71 0)
			(layer "B.Fab")
			(hide yes)
			(effects
				(font
					(size 1 1)
					(thickness 0.15)
				)
				(justify mirror)
			)
		)
		(property "License" "Apache-2.0"
			(at 85.49 362.71 0)
			(layer "B.Fab")
			(hide yes)
			(effects
				(font
					(size 1 1)
					(thickness 0.15)
				)
				(justify mirror)
			)
		)
		(property "MPN" "CR0402-FX-1002GLF"
			(at 85.49 362.71 0)
			(layer "B.Fab")
			(hide yes)
			(effects
				(font
					(size 1 1)
					(thickness 0.15)
				)
				(justify mirror)
			)
		)
		(property "Manufacturer" "Bourns"
			(at 85.49 362.71 0)
			(layer "B.Fab")
			(hide yes)
			(effects
				(font
					(size 1 1)
					(thickness 0.15)
				)
				(justify mirror)
			)
		)
		(property "Public" ""
			(at 85.49 362.71 0)
			(layer "B.Fab")
			(hide yes)
			(effects
				(font
					(size 1 1)
					(thickness 0.15)
				)
				(justify mirror)
			)
		)
		(property "Tolerance" "1%"
			(at 85.49 362.71 0)
			(layer "B.Fab")
			(hide yes)
			(effects
				(font
					(size 1 1)
					(thickness 0.15)
				)
				(justify mirror)
			)
		)
		(property "Val" "10k"
			(at 85.49 362.71 0)
			(layer "B.Fab")
			(hide yes)
			(effects
				(font
					(size 1 1)
					(thickness 0.15)
				)
				(justify mirror)
			)
		)
		(sheetname "/Memory/")
		(sheetfile "memory.kicad_sch")
		(attr smd)
		(fp_rect
			(start -0.925 0.47)
			(end 0.925 -0.47)
			(stroke
				(width 0.05)
				(type default)
			)
			(fill no)
			(layer "B.CrtYd")
		)
		(fp_rect
			(start -0.5 0.25)
			(end 0.5 -0.25)
			(stroke
				(width 0.15)
				(type solid)
			)
			(fill no)
			(layer "B.Fab")
		)
		(fp_text user "Author: Antmicro"
			(at -0.95 -4.169 90)
			(layer "B.Fab")
			(effects
				(font
					(size 0.7 0.7)
					(thickness 0.15)
				)
				(justify left bottom mirror)
			)
		)
		(fp_text user "License: Apache-2.0"
			(at -0.95 -5.169 90)
			(layer "B.Fab")
			(effects
				(font
					(size 0.7 0.7)
					(thickness 0.15)
				)
				(justify left bottom mirror)
			)
		)
		(fp_text user "${REFERENCE}"
			(at -0.95 -3.168 90)
			(layer "B.Fab")
			(effects
				(font
					(size 0.7 0.7)
					(thickness 0.15)
				)
				(justify left bottom mirror)
			)
		)
		(pad "1" smd roundrect
			(at -0.48 0 270)
			(size 0.59 0.64)
			(layers "B.Cu" "B.Mask" "B.Paste")
			(roundrect_rratio 0.25)
			(net 246 "SD_VDD_OVERRIDE")
			(pintype "passive")
		)
		(pad "2" smd roundrect
			(at 0.48 0 270)
			(size 0.59 0.64)
			(layers "B.Cu" "B.Mask" "B.Paste")
			(roundrect_rratio 0.25)
			(net 417 "GND")
			(pintype "passive")
		)
	)
)
